# T6G (Grand Teton) — schematic netlist excerpt (pin names and nets, part order shuffled) for the footprints in the layout excerpt that follows; sources: Cadence DE-HDL packaged netlist, KiCad conversion of 04192023_DAF0TMB3IC0_F0TG_MB_C_brd_V02_OCP.brd

U36  TCA9548APWR  IC  pkg TSSOP24XA  page 250
  A0  = PCA9548_PCIE3_ADDR0
  A1  = PCA9548_PCIE3_ADDR1
  \reset#\  = PU_RST_SMB_PCIE0_N
  SD0  = SMB_USB_CPU0_HUB1_SDA_R
  SC0  = SMB_USB_CPU0_HUB1_SCL_R
  SD1  = SMB_IOEXP_3V3AUX_SDA_R
  SC1  = SMB_IOEXP_3V3AUX_SCL_R
  SD2  = SMB_PCIE0_3V3AUX_SDA_R3
  SC2  = SMB_PCIE0_3V3AUX_SCL_R3
  SD3  = SMB_PCIE0_3V3AUX_SDA_R5
  SC3  = SMB_PCIE0_3V3AUX_SCL_R5
  GND  = GND
  SD4  = SMB_BMC_SWB_SDA_R4
  SC4  = SMB_BMC_SWB_SCL_R4
  SD5  = SMB_FRU_3V3AUX_SDA_R
  SC5  = SMB_FRU_3V3AUX_SCL_R
  SD6  = SMB_INA230_3V3AUX_SDA_R
  SC6  = SMB_INA230_3V3AUX_SCL_R
  SD7  = NC
  SC7  = NC
  A2  = PCA9548_PCIE3_ADDR2
  SCL  = SMB_PCIE0_3V3AUX_SCL_R
  SDA  = SMB_PCIE0_3V3AUX_SDA_R
  VCC  = P3V3_AUX

R886  Q_RES  4.7K 5% EMPTY  pkg 0201LF  page 342 : A = MODE_RT_CPU1_P2 ; B = GND

(kicad_pcb
	(version 20260206)
	(generator "pcbnew")
	(generator_version "10.0")
	(general
		(thickness 1.6)
		(legacy_teardrops no)
	)
	(paper "A4")
	(title_block
		(title "04192023_DAF0TMB3IC0_F0TG_MB_C_brd_V02_OCP.brd")
		(comment 1 "Grand Teton / footprints 2513-2514 of 8354")
	)
	(layers
		(0 "F.Cu" signal "TOP")
		(4 "In1.Cu" signal "GND")
		(6 "In2.Cu" signal "IN1")
		(8 "In3.Cu" signal "GND1")
		(10 "In4.Cu" signal "IN2")
		(12 "In5.Cu" signal "GND2")
		(14 "In6.Cu" signal "IN3")
		(16 "In7.Cu" signal "GND3")
		(18 "In8.Cu" signal "VCC")
		(20 "In9.Cu" signal "VCC1")
		(22 "In10.Cu" signal "GND4")
		(24 "In11.Cu" signal "IN4")
		(26 "In12.Cu" signal "GND5")
		(28 "In13.Cu" signal "IN5")
		(30 "In14.Cu" signal "GND6")
		(32 "In15.Cu" signal "IN6")
		(34 "In16.Cu" signal "GND7")
		(2 "B.Cu" signal "BOTTOM")
		(9 "F.Adhes" user "F.Adhesive")
		(11 "B.Adhes" user "B.Adhesive")
		(13 "F.Paste" user "Package Geometry/Pastemask Top")
		(15 "B.Paste" user "Package Geometry/Pastemask Bottom")
		(5 "F.SilkS" user "Ref Des/Silkscreen Top")
		(7 "B.SilkS" user "Ref Des/Silkscreen Bottom")
		(1 "F.Mask" user "Board Geometry/Soldermask Top")
		(3 "B.Mask" user "Board Geometry/Soldermask Bottom")
		(17 "Dwgs.User" user "User.Drawings")
		(19 "Cmts.User" user "User.Comments")
		(21 "Eco1.User" user "User.Eco1")
		(23 "Eco2.User" user "User.Eco2")
		(25 "Edge.Cuts" user "Board Geometry/Outline")
		(27 "Margin" user)
		(31 "F.CrtYd" user "Package Geometry/Place Bound Top")
		(29 "B.CrtYd" user "Package Geometry/Place Bound Bottom")
		(35 "F.Fab" user "Ref Des/Assembly Top")
		(33 "B.Fab" user "Ref Des/Assembly Bottom")
	)
	(footprint ""
		(layer "F.Cu")
		(at 145.128488 -394.166852 -90)
		(property "Reference" "R886"
			(at 0 0 270)
			(layer "F.SilkS")
			(hide yes)
			(effects
				(font
					(size 1.27 1.27)
				)
			)
		)
		(property "Value" ""
			(at 0 0 270)
			(layer "F.Fab")
			(effects
				(font
					(size 1.27 1.27)
				)
			)
		)
		(duplicate_pad_numbers_are_jumpers no)
		(fp_line
			(start -0.32512 0.175006)
			(end -0.32512 -0.175006)
			(stroke
				(width 0.1)
				(type default)
			)
			(layer "F.Fab")
		)
		(fp_line
			(start 0.32512 0.175006)
			(end -0.32512 0.175006)
			(stroke
				(width 0.1)
				(type default)
			)
			(layer "F.Fab")
		)
		(fp_line
			(start -0.32512 -0.175006)
			(end 0.32512 -0.175006)
			(stroke
				(width 0.1)
				(type default)
			)
			(layer "F.Fab")
		)
		(fp_line
			(start 0.32512 -0.175006)
			(end 0.32512 0.175006)
			(stroke
				(width 0.1)
				(type default)
			)
			(layer "F.Fab")
		)
		(pad "1" smd rect
			(at -0.2667 0 270)
			(size 0.3048 0.381)
			(layers "F.Cu" "F.Mask" "F.Paste")
			(net "MODE_RT_CPU1_P2")
		)
		(pad "2" smd rect
			(at 0.2667 0 90)
			(size 0.3048 0.381)
			(layers "F.Cu" "F.Mask" "F.Paste")
			(net "GND")
		)
	)
	(footprint ""
		(layer "F.Cu")
		(at 286.928052 -119.207026)
		(property "Reference" "U36"
			(at -2.1844 -4.587748 0)
			(unlocked yes)
			(layer "F.SilkS")
			(effects
				(font
					(size 0.7874 0.5842)
					(thickness 0.1524)
				)
				(justify left)
			)
		)
		(property "Value" ""
			(at 0 0 0)
			(layer "F.Fab")
			(effects
				(font
					(size 1.27 1.27)
				)
			)
		)
		(duplicate_pad_numbers_are_jumpers no)
		(fp_line
			(start -1.8542 -3.949954)
			(end -1.8542 3.949954)
			(stroke
				(width 0.1524)
				(type default)
			)
			(layer "F.SilkS")
		)
		(fp_line
			(start -1.8542 3.949954)
			(end 1.8542 3.949954)
			(stroke
				(width 0.1524)
				(type default)
			)
			(layer "F.SilkS")
		)
		(fp_line
			(start -1.282954 -3.949954)
			(end -1.8542 -3.949954)
			(stroke
				(width 0.1524)
				(type default)
			)
			(layer "F.SilkS")
		)
		(fp_line
			(start 0 -2.667)
			(end -1.282954 -3.949954)
			(stroke
				(width 0.1524)
				(type default)
			)
			(layer "F.SilkS")
		)
		(fp_line
			(start 1.282954 -3.949954)
			(end 0 -2.667)
			(stroke
				(width 0.1524)
				(type default)
			)
			(layer "F.SilkS")
		)
		(fp_line
			(start 1.8542 -3.949954)
			(end 1.282954 -3.949954)
			(stroke
				(width 0.1524)
				(type default)
			)
			(layer "F.SilkS")
		)
		(fp_line
			(start 1.8542 3.949954)
			(end 1.8542 -3.949954)
			(stroke
				(width 0.1524)
				(type default)
			)
			(layer "F.SilkS")
		)
		(fp_poly
			(pts
				(xy -3.074416 -3.996182) (xy -3.582416 -5.012182) (xy -2.566416 -5.012182)
			)
			(stroke
				(width 0)
				(type default)
			)
			(fill yes)
			(layer "F.SilkS")
		)
		(fp_line
			(start -2.249932 -3.949954)
			(end -2.249932 3.949954)
			(stroke
				(width 0.1)
				(type default)
			)
			(layer "F.Fab")
		)
		(fp_line
			(start -2.249932 3.949954)
			(end 2.249932 3.949954)
			(stroke
				(width 0.1)
				(type default)
			)
			(layer "F.Fab")
		)
		(fp_line
			(start 2.249932 -3.949954)
			(end -2.249932 -3.949954)
			(stroke
				(width 0.1)
				(type default)
			)
			(layer "F.Fab")
		)
		(fp_line
			(start 2.249932 3.949954)
			(end 2.249932 -3.949954)
			(stroke
				(width 0.1)
				(type default)
			)
			(layer "F.Fab")
		)
		(fp_poly
			(pts
				(xy -4.8006 -4.08305) (xy -4.8006 -3.06705) (xy -3.7846 -3.57505)
			)
			(stroke
				(width 0)
				(type default)
			)
			(fill yes)
			(layer "F.Fab")
		)
		(pad "1" smd rect
			(at -2.800096 -3.57505 270)
			(size 0.3048 1.6002)
			(layers "F.Cu" "F.Mask" "F.Paste")
			(net "PCA9548_PCIE3_ADDR0")
		)
		(pad "2" smd rect
			(at -2.800096 -2.925064 270)
			(size 0.3048 1.6002)
			(layers "F.Cu" "F.Mask" "F.Paste")
			(net "PCA9548_PCIE3_ADDR1")
		)
		(pad "3" smd rect
			(at -2.800096 -2.275078 270)
			(size 0.3048 1.6002)
			(layers "F.Cu" "F.Mask" "F.Paste")
			(net "PU_RST_SMB_PCIE0_N")
		)
		(pad "4" smd rect
			(at -2.800096 -1.625092 270)
			(size 0.3048 1.6002)
			(layers "F.Cu" "F.Mask" "F.Paste")
			(net "SMB_USB_CPU0_HUB1_SDA_R")
		)
		(pad "5" smd rect
			(at -2.800096 -0.975106 270)
			(size 0.3048 1.6002)
			(layers "F.Cu" "F.Mask" "F.Paste")
			(net "SMB_USB_CPU0_HUB1_SCL_R")
		)
		(pad "6" smd rect
			(at -2.800096 -0.32512 270)
			(size 0.3048 1.6002)
			(layers "F.Cu" "F.Mask" "F.Paste")
			(net "SMB_IOEXP_3V3AUX_SDA_R")
		)
		(pad "7" smd rect
			(at -2.800096 0.32512 270)
			(size 0.3048 1.6002)
			(layers "F.Cu" "F.Mask" "F.Paste")
			(net "SMB_IOEXP_3V3AUX_SCL_R")
		)
		(pad "8" smd rect
			(at -2.800096 0.975106 270)
			(size 0.3048 1.6002)
			(layers "F.Cu" "F.Mask" "F.Paste")
			(net "SMB_PCIE0_3V3AUX_SDA_R3")
		)
		(pad "9" smd rect
			(at -2.800096 1.625092 270)
			(size 0.3048 1.6002)
			(layers "F.Cu" "F.Mask" "F.Paste")
			(net "SMB_PCIE0_3V3AUX_SCL_R3")
		)
		(pad "10" smd rect
			(at -2.800096 2.275078 270)
			(size 0.3048 1.6002)
			(layers "F.Cu" "F.Mask" "F.Paste")
			(net "SMB_PCIE0_3V3AUX_SDA_R5")
		)
		(pad "11" smd rect
			(at -2.800096 2.925064 270)
			(size 0.3048 1.6002)
			(layers "F.Cu" "F.Mask" "F.Paste")
			(net "SMB_PCIE0_3V3AUX_SCL_R5")
		)
		(pad "12" smd rect
			(at -2.800096 3.57505 270)
			(size 0.3048 1.6002)
			(layers "F.Cu" "F.Mask" "F.Paste")
			(net "GND")
		)
		(pad "13" smd rect
			(at 2.800096 3.57505 270)
			(size 0.3048 1.6002)
			(layers "F.Cu" "F.Mask" "F.Paste")
			(net "SMB_BMC_SWB_SDA_R4")
		)
		(pad "14" smd rect
			(at 2.800096 2.925064 270)
			(size 0.3048 1.6002)
			(layers "F.Cu" "F.Mask" "F.Paste")
			(net "SMB_BMC_SWB_SCL_R4")
		)
		(pad "15" smd rect
			(at 2.800096 2.275078 270)
			(size 0.3048 1.6002)
			(layers "F.Cu" "F.Mask" "F.Paste")
			(net "SMB_FRU_3V3AUX_SDA_R")
		)
		(pad "16" smd rect
			(at 2.800096 1.625092 270)
			(size 0.3048 1.6002)
			(layers "F.Cu" "F.Mask" "F.Paste")
			(net "SMB_FRU_3V3AUX_SCL_R")
		)
		(pad "17" smd rect
			(at 2.800096 0.975106 270)
			(size 0.3048 1.6002)
			(layers "F.Cu" "F.Mask" "F.Paste")
			(net "SMB_INA230_3V3AUX_SDA_R")
		)
		(pad "18" smd rect
			(at 2.800096 0.32512 270)
			(size 0.3048 1.6002)
			(layers "F.Cu" "F.Mask" "F.Paste")
			(net "SMB_INA230_3V3AUX_SCL_R")
		)
		(pad "19" smd rect
			(at 2.800096 -0.32512 270)
			(size 0.3048 1.6002)
			(layers "F.Cu" "F.Mask" "F.Paste")
			(net "Net_10757")
		)
		(pad "20" smd rect
			(at 2.800096 -0.975106 270)
			(size 0.3048 1.6002)
			(layers "F.Cu" "F.Mask" "F.Paste")
			(net "Net_10758")
		)
		(pad "21" smd rect
			(at 2.800096 -1.625092 270)
			(size 0.3048 1.6002)
			(layers "F.Cu" "F.Mask" "F.Paste")
			(net "PCA9548_PCIE3_ADDR2")
		)
		(pad "22" smd rect
			(at 2.800096 -2.275078 270)
			(size 0.3048 1.6002)
			(layers "F.Cu" "F.Mask" "F.Paste")
			(net "SMB_PCIE0_3V3AUX_SCL_R")
		)
		(pad "23" smd rect
			(at 2.800096 -2.925064 270)
			(size 0.3048 1.6002)
			(layers "F.Cu" "F.Mask" "F.Paste")
			(net "SMB_PCIE0_3V3AUX_SDA_R")
		)
		(pad "24" smd rect
			(at 2.800096 -3.57505 270)
			(size 0.3048 1.6002)
			(layers "F.Cu" "F.Mask" "F.Paste")
			(net "P3V3_AUX")
		)
	)
)
